(kicad_pcb
	(version 20241229)
	(generator "pcbnew")
	(generator_version "9.0")
	(general
		(thickness 1.294)
		(legacy_teardrops no)
	)
	(paper "A3")
	(title_block
		(title "Kintex 410T devboard")
		(date "2024-04-03")
		(rev "1.1.2")
		(comment 9 "footprint 170 of 975 (U1), pads 537-596 of 900")
	)
	(layers
		(0 "F.Cu" mixed)
		(4 "In1.Cu" power)
		(6 "In2.Cu" power)
		(8 "In3.Cu" mixed)
		(10 "In4.Cu" power)
		(12 "In5.Cu" mixed)
		(14 "In6.Cu" power)
		(16 "In7.Cu" mixed)
		(18 "In8.Cu" power)
		(2 "B.Cu" mixed)
		(9 "F.Adhes" user "F.Adhesive")
		(11 "B.Adhes" user "B.Adhesive")
		(13 "F.Paste" user)
		(15 "B.Paste" user)
		(5 "F.SilkS" user "F.Silkscreen")
		(7 "B.SilkS" user "B.Silkscreen")
		(1 "F.Mask" user)
		(3 "B.Mask" user)
		(17 "Dwgs.User" user "User.Drawings")
		(19 "Cmts.User" user "User.Comments")
		(21 "Eco1.User" user "User.Eco1")
		(23 "Eco2.User" user "User.Eco2")
		(25 "Edge.Cuts" user)
		(27 "Margin" user)
		(31 "F.CrtYd" user "F.Courtyard")
		(29 "B.CrtYd" user "B.Courtyard")
		(35 "F.Fab" user)
		(33 "B.Fab" user)
	)
	(footprint "antmicro-footprints:BGA-900_31x31mm_Layout30x30_P1x1mm_FFG900"
		(locked yes)
		(layer "F.Cu")
		(at 200 130)
		(property "Reference" "U1"
			(at -15.74 -15.78 0)
			(layer "F.SilkS")
			(effects
				(font
					(size 0.7 0.7)
					(thickness 0.15)
				)
				(justify left bottom)
			)
		)
		(property "Value" "XC7K410T-2FFG900I"
			(at -4.436 17.635 0)
			(layer "F.Fab")
			(effects
				(font
					(size 0.7 0.7)
					(thickness 0.15)
				)
				(justify left bottom)
			)
		)
		(property "Description" "FPGA, Kintex-7, MMCM, PLL, 350 I/O's, 710 MHz, 406720 Cells, 970 mV to 1.03 V, FCBGA-900"
			(at 0 0 0)
			(layer "F.Fab")
			(hide yes)
			(effects
				(font
					(size 1.27 1.27)
					(thickness 0.15)
				)
			)
		)
		(property "Author" "Antmicro"
			(at 0 0 0)
			(layer "F.Fab")
			(hide yes)
			(effects
				(font
					(size 1 1)
					(thickness 0.15)
				)
			)
		)
		(property "License" "Apache-2.0"
			(at 0 0 0)
			(layer "F.Fab")
			(hide yes)
			(effects
				(font
					(size 1 1)
					(thickness 0.15)
				)
			)
		)
		(property "MPN" "XC7K410T-2FFG900I"
			(at 0 0 0)
			(layer "F.Fab")
			(hide yes)
			(effects
				(font
					(size 1 1)
					(thickness 0.15)
				)
			)
		)
		(property "Manufacturer" "AMD-Xilinx"
			(at 0 0 0)
			(layer "F.Fab")
			(hide yes)
			(effects
				(font
					(size 1 1)
					(thickness 0.15)
				)
			)
		)
		(sheetname "FPGA supply")
		(sheetfile "fpga-supply.kicad_sch")
		(attr smd)
		(pad "H27" smd circle
			(at 11.5 -7.5)
			(size 0.5 0.5)
			(property pad_prop_bga)
			(layers "F.Cu" "F.Mask" "F.Paste")
			(net 430 "/FPGA Bank 16 & 17/USR_FLASH_1.DQ1")
			(pinfunction "IO_L23N_T3_16")
			(pintype "bidirectional")
			(die_length 17.224)
			(solder_mask_margin 0.02)
		)
		(pad "H28" smd circle
			(at 12.5 -7.5)
			(size 0.5 0.5)
			(property pad_prop_bga)
			(layers "F.Cu" "F.Mask" "F.Paste")
			(net 3 "VCC_USR_B")
			(pinfunction "VCCO_16")
			(pintype "passive")
			(solder_mask_margin 0.02)
		)
		(pad "H29" smd circle
			(at 13.5 -7.5)
			(size 0.5 0.5)
			(property pad_prop_bga)
			(layers "F.Cu" "F.Mask" "F.Paste")
			(net 1241 "/USER_IO.A13")
			(pinfunction "IO_L7N_T1_AD10N_15")
			(pintype "bidirectional")
			(die_length 19.337)
			(solder_mask_margin 0.02)
		)
		(pad "H30" smd circle
			(at 14.5 -7.5)
			(size 0.5 0.5)
			(property pad_prop_bga)
			(layers "F.Cu" "F.Mask" "F.Paste")
			(net 1287 "/USER_IO.B27")
			(pinfunction "IO_L24P_T3_16")
			(pintype "bidirectional")
			(die_length 21.292)
			(solder_mask_margin 0.02)
		)
		(pad "J1" smd circle
			(at -14.5 -6.5)
			(size 0.5 0.5)
			(property pad_prop_bga)
			(layers "F.Cu" "F.Mask" "F.Paste")
			(net 1 "GND")
			(pinfunction "GND")
			(pintype "passive")
			(solder_mask_margin 0.02)
		)
		(pad "J2" smd circle
			(at -13.5 -6.5)
			(size 0.5 0.5)
			(property pad_prop_bga)
			(layers "F.Cu" "F.Mask" "F.Paste")
			(net 1 "GND")
			(pinfunction "GND")
			(pintype "passive")
			(solder_mask_margin 0.02)
		)
		(pad "J3" smd circle
			(at -12.5 -6.5)
			(size 0.5 0.5)
			(property pad_prop_bga)
			(layers "F.Cu" "F.Mask" "F.Paste")
			(net 1026 "unconnected-(U1G-MGTXTXN1_117-PadJ3)")
			(pinfunction "MGTXTXN1_117")
			(pintype "bidirectional+no_connect")
			(die_length 11.925)
			(solder_mask_margin 0.02)
		)
		(pad "J4" smd circle
			(at -11.5 -6.5)
			(size 0.5 0.5)
			(property pad_prop_bga)
			(layers "F.Cu" "F.Mask" "F.Paste")
			(net 1027 "unconnected-(U1G-MGTXTXP1_117-PadJ4)")
			(pinfunction "MGTXTXP1_117")
			(pintype "bidirectional+no_connect")
			(die_length 11.887)
			(solder_mask_margin 0.02)
		)
		(pad "J5" smd circle
			(at -10.5 -6.5)
			(size 0.5 0.5)
			(property pad_prop_bga)
			(layers "F.Cu" "F.Mask" "F.Paste")
			(net 8 "+1V2_MGTAVTT")
			(pinfunction "MGTAVTT")
			(pintype "passive")
			(solder_mask_margin 0.02)
		)
		(pad "J6" smd circle
			(at -9.5 -6.5)
			(size 0.5 0.5)
			(property pad_prop_bga)
			(layers "F.Cu" "F.Mask" "F.Paste")
			(net 1 "GND")
			(pinfunction "GND")
			(pintype "passive")
			(solder_mask_margin 0.02)
		)
		(pad "J7" smd circle
			(at -8.5 -6.5)
			(size 0.5 0.5)
			(property pad_prop_bga)
			(layers "F.Cu" "F.Mask" "F.Paste")
			(net 1028 "unconnected-(U1G-MGTREFCLK1N_117-PadJ7)")
			(pinfunction "MGTREFCLK1N_117")
			(pintype "bidirectional+no_connect")
			(die_length 9.91)
			(solder_mask_margin 0.02)
		)
		(pad "J8" smd circle
			(at -7.5 -6.5)
			(size 0.5 0.5)
			(property pad_prop_bga)
			(layers "F.Cu" "F.Mask" "F.Paste")
			(net 1029 "unconnected-(U1G-MGTREFCLK1P_117-PadJ8)")
			(pinfunction "MGTREFCLK1P_117")
			(pintype "bidirectional+no_connect")
			(die_length 9.161)
			(solder_mask_margin 0.02)
		)
		(pad "J9" smd circle
			(at -6.5 -6.5)
			(size 0.5 0.5)
			(property pad_prop_bga)
			(layers "F.Cu" "F.Mask" "F.Paste")
			(net 1 "GND")
			(pinfunction "GND")
			(pintype "passive")
			(solder_mask_margin 0.02)
		)
		(pad "J10" smd circle
			(at -5.5 -6.5)
			(size 0.5 0.5)
			(property pad_prop_bga)
			(layers "F.Cu" "F.Mask" "F.Paste")
			(net 1 "GND")
			(pinfunction "GND")
			(pintype "passive")
			(solder_mask_margin 0.02)
		)
		(pad "J11" smd circle
			(at -4.5 -6.5)
			(size 0.5 0.5)
			(property pad_prop_bga)
			(layers "F.Cu" "F.Mask" "F.Paste")
			(net 392 "/FMC+ HSPC/FMC.IO8_P")
			(pinfunction "IO_L8P_T1_18")
			(pintype "bidirectional")
			(die_length 21.323)
			(solder_mask_margin 0.02)
		)
		(pad "J12" smd circle
			(at -3.5 -6.5)
			(size 0.5 0.5)
			(property pad_prop_bga)
			(layers "F.Cu" "F.Mask" "F.Paste")
			(net 388 "/FMC+ HSPC/FMC.IO8_N")
			(pinfunction "IO_L8N_T1_18")
			(pintype "bidirectional")
			(die_length 20.125)
			(solder_mask_margin 0.02)
		)
		(pad "J13" smd circle
			(at -2.5 -6.5)
			(size 0.5 0.5)
			(property pad_prop_bga)
			(layers "F.Cu" "F.Mask" "F.Paste")
			(net 460 "/FMC+ HSPC/FMC.IO4_N")
			(pinfunction "IO_L4N_T0_18")
			(pintype "bidirectional")
			(die_length 18.187)
			(solder_mask_margin 0.02)
		)
		(pad "J14" smd circle
			(at -1.5 -6.5)
			(size 0.5 0.5)
			(property pad_prop_bga)
			(layers "F.Cu" "F.Mask" "F.Paste")
			(net 440 "/FMC+ HSPC/FMC.IO5_N")
			(pinfunction "IO_L5N_T0_18")
			(pintype "bidirectional")
			(die_length 17.741)
			(solder_mask_margin 0.02)
		)
		(pad "J15" smd circle
			(at -0.5 -6.5)
			(size 0.5 0.5)
			(property pad_prop_bga)
			(layers "F.Cu" "F.Mask" "F.Paste")
			(net 24 "+3V3")
			(pinfunction "VCCO_18")
			(pintype "passive")
			(solder_mask_margin 0.02)
		)
		(pad "J16" smd circle
			(at 0.5 -6.5)
			(size 0.5 0.5)
			(property pad_prop_bga)
			(layers "F.Cu" "F.Mask" "F.Paste")
			(net 381 "/FMC+ HSPC/FMC.IO9_P")
			(pinfunction "IO_L9P_T1_DQS_18")
			(pintype "bidirectional")
			(die_length 18.593)
			(solder_mask_margin 0.02)
		)
		(pad "J17" smd circle
			(at 1.5 -6.5)
			(size 0.5 0.5)
			(property pad_prop_bga)
			(layers "F.Cu" "F.Mask" "F.Paste")
			(net 1030 "unconnected-(U1C-IO_L3P_T0_DQS_17-PadJ17)")
			(pinfunction "IO_L3P_T0_DQS_17")
			(pintype "bidirectional+no_connect")
			(die_length 10.515)
			(solder_mask_margin 0.02)
		)
		(pad "J18" smd circle
			(at 2.5 -6.5)
			(size 0.5 0.5)
			(property pad_prop_bga)
			(layers "F.Cu" "F.Mask" "F.Paste")
			(net 1031 "unconnected-(U1C-IO_L1N_T0_17-PadJ18)")
			(pinfunction "IO_L1N_T0_17")
			(pintype "bidirectional+no_connect")
			(die_length 8.317)
			(solder_mask_margin 0.02)
		)
		(pad "J19" smd circle
			(at 3.5 -6.5)
			(size 0.5 0.5)
			(property pad_prop_bga)
			(layers "F.Cu" "F.Mask" "F.Paste")
			(net 514 "/FMC+ HSPC/FMC.CLK_DIR")
			(pinfunction "IO_L4P_T0_17")
			(pintype "bidirectional")
			(die_length 9.052)
			(solder_mask_margin 0.02)
		)
		(pad "J20" smd circle
			(at 4.5 -6.5)
			(size 0.5 0.5)
			(property pad_prop_bga)
			(layers "F.Cu" "F.Mask" "F.Paste")
			(net 1 "GND")
			(pinfunction "GND")
			(pintype "passive")
			(solder_mask_margin 0.02)
		)
		(pad "J21" smd circle
			(at 5.5 -6.5)
			(size 0.5 0.5)
			(property pad_prop_bga)
			(layers "F.Cu" "F.Mask" "F.Paste")
			(net 1032 "unconnected-(U1B-IO_L5P_T0_AD2P_15-PadJ21)")
			(pinfunction "IO_L5P_T0_AD2P_15")
			(pintype "bidirectional+no_connect")
			(die_length 12.084)
			(solder_mask_margin 0.02)
		)
		(pad "J22" smd circle
			(at 6.5 -6.5)
			(size 0.5 0.5)
			(property pad_prop_bga)
			(layers "F.Cu" "F.Mask" "F.Paste")
			(net 1252 "/USER_IO.A26")
			(pinfunction "IO_L5N_T0_AD2N_15")
			(pintype "bidirectional")
			(die_length 11.925)
			(solder_mask_margin 0.02)
		)
		(pad "J23" smd circle
			(at 7.5 -6.5)
			(size 0.5 0.5)
			(property pad_prop_bga)
			(layers "F.Cu" "F.Mask" "F.Paste")
			(net 1033 "unconnected-(U1B-IO_L1P_T0_AD0P_15-PadJ23)")
			(pinfunction "IO_L1P_T0_AD0P_15")
			(pintype "bidirectional+no_connect")
			(die_length 15.063)
			(solder_mask_margin 0.02)
		)
		(pad "J24" smd circle
			(at 8.5 -6.5)
			(size 0.5 0.5)
			(property pad_prop_bga)
			(layers "F.Cu" "F.Mask" "F.Paste")
			(net 1034 "unconnected-(U1B-IO_L1N_T0_AD0N_15-PadJ24)")
			(pinfunction "IO_L1N_T0_AD0N_15")
			(pintype "bidirectional+no_connect")
			(die_length 14.83)
			(solder_mask_margin 0.02)
		)
		(pad "J25" smd circle
			(at 9.5 -6.5)
			(size 0.5 0.5)
			(property pad_prop_bga)
			(layers "F.Cu" "F.Mask" "F.Paste")
			(net 2 "VCC_USR_A")
			(pinfunction "VCCO_15")
			(pintype "bidirectional")
			(solder_mask_margin 0.02)
		)
		(pad "J26" smd circle
			(at 10.5 -6.5)
			(size 0.5 0.5)
			(property pad_prop_bga)
			(layers "F.Cu" "F.Mask" "F.Paste")
			(net 1246 "/USER_IO.A17")
			(pinfunction "IO_L10N_T1_AD4N_15")
			(pintype "bidirectional")
			(die_length 18.197)
			(solder_mask_margin 0.02)
		)
		(pad "J27" smd circle
			(at 11.5 -6.5)
			(size 0.5 0.5)
			(property pad_prop_bga)
			(layers "F.Cu" "F.Mask" "F.Paste")
			(net 1240 "/USER_IO.A12")
			(pinfunction "IO_L8P_T1_AD3P_15")
			(pintype "bidirectional")
			(die_length 18.459)
			(solder_mask_margin 0.02)
		)
		(pad "J28" smd circle
			(at 12.5 -6.5)
			(size 0.5 0.5)
			(property pad_prop_bga)
			(layers "F.Cu" "F.Mask" "F.Paste")
			(net 1242 "/USER_IO.A14")
			(pinfunction "IO_L8N_T1_AD3N_15")
			(pintype "bidirectional")
			(die_length 18.849)
			(solder_mask_margin 0.02)
		)
		(pad "J29" smd circle
			(at 13.5 -6.5)
			(size 0.5 0.5)
			(property pad_prop_bga)
			(layers "F.Cu" "F.Mask" "F.Paste")
			(net 1238 "/USER_IO.A9")
			(pinfunction "IO_L7P_T1_AD10P_15")
			(pintype "bidirectional")
			(die_length 17.885)
			(solder_mask_margin 0.02)
		)
		(pad "J30" smd circle
			(at 14.5 -6.5)
			(size 0.5 0.5)
			(property pad_prop_bga)
			(layers "F.Cu" "F.Mask" "F.Paste")
			(net 1 "GND")
			(pinfunction "GND")
			(pintype "passive")
			(solder_mask_margin 0.02)
		)
		(pad "K1" smd circle
			(at -14.5 -5.5)
			(size 0.5 0.5)
			(property pad_prop_bga)
			(layers "F.Cu" "F.Mask" "F.Paste")
			(net 1035 "unconnected-(U1G-MGTXTXN0_117-PadK1)")
			(pinfunction "MGTXTXN0_117")
			(pintype "bidirectional+no_connect")
			(die_length 14.162)
			(solder_mask_margin 0.02)
		)
		(pad "K2" smd circle
			(at -13.5 -5.5)
			(size 0.5 0.5)
			(property pad_prop_bga)
			(layers "F.Cu" "F.Mask" "F.Paste")
			(net 1036 "unconnected-(U1G-MGTXTXP0_117-PadK2)")
			(pinfunction "MGTXTXP0_117")
			(pintype "bidirectional+no_connect")
			(die_length 14.111)
			(solder_mask_margin 0.02)
		)
		(pad "K3" smd circle
			(at -12.5 -5.5)
			(size 0.5 0.5)
			(property pad_prop_bga)
			(layers "F.Cu" "F.Mask" "F.Paste")
			(net 8 "+1V2_MGTAVTT")
			(pinfunction "MGTAVTT")
			(pintype "passive")
			(solder_mask_margin 0.02)
		)
		(pad "K4" smd circle
			(at -11.5 -5.5)
			(size 0.5 0.5)
			(property pad_prop_bga)
			(layers "F.Cu" "F.Mask" "F.Paste")
			(net 1 "GND")
			(pinfunction "GND")
			(pintype "passive")
			(solder_mask_margin 0.02)
		)
		(pad "K5" smd circle
			(at -10.5 -5.5)
			(size 0.5 0.5)
			(property pad_prop_bga)
			(layers "F.Cu" "F.Mask" "F.Paste")
			(net 1037 "unconnected-(U1G-MGTXRXN0_117-PadK5)")
			(pinfunction "MGTXRXN0_117")
			(pintype "bidirectional+no_connect")
			(die_length 9.726)
			(solder_mask_margin 0.02)
		)
		(pad "K6" smd circle
			(at -9.5 -5.5)
			(size 0.5 0.5)
			(property pad_prop_bga)
			(layers "F.Cu" "F.Mask" "F.Paste")
			(net 1038 "unconnected-(U1G-MGTXRXP0_117-PadK6)")
			(pinfunction "MGTXRXP0_117")
			(pintype "bidirectional+no_connect")
			(die_length 9.905)
			(solder_mask_margin 0.02)
		)
		(pad "K7" smd circle
			(at -8.5 -5.5)
			(size 0.5 0.5)
			(property pad_prop_bga)
			(layers "F.Cu" "F.Mask" "F.Paste")
			(net 6 "+1V0_MGTAVCC")
			(pinfunction "MGTAVCC")
			(pintype "passive")
			(solder_mask_margin 0.02)
		)
		(pad "K8" smd circle
			(at -7.5 -5.5)
			(size 0.5 0.5)
			(property pad_prop_bga)
			(layers "F.Cu" "F.Mask" "F.Paste")
			(net 1 "GND")
			(pinfunction "GND")
			(pintype "passive")
			(solder_mask_margin 0.02)
		)
		(pad "K9" smd circle
			(at -6.5 -5.5)
			(size 0.5 0.5)
			(property pad_prop_bga)
			(layers "F.Cu" "F.Mask" "F.Paste")
			(net 1 "GND")
			(pinfunction "GND")
			(pintype "passive")
			(solder_mask_margin 0.02)
		)
		(pad "K10" smd circle
			(at -5.5 -5.5)
			(size 0.5 0.5)
			(property pad_prop_bga)
			(layers "F.Cu" "F.Mask" "F.Paste")
			(net 301 "/FPGA Config/PROGRAM_B")
			(pinfunction "PROGRAM_B_0")
			(pintype "bidirectional")
			(die_length 20.153)
			(solder_mask_margin 0.02)
		)
		(pad "K11" smd circle
			(at -4.5 -5.5)
			(size 0.5 0.5)
			(property pad_prop_bga)
			(layers "F.Cu" "F.Mask" "F.Paste")
			(net 401 "/FMC+ HSPC/FMC.IO6_N")
			(pinfunction "IO_L6N_T0_VREF_18")
			(pintype "bidirectional")
			(die_length 21.727)
			(solder_mask_margin 0.02)
		)
		(pad "K12" smd circle
			(at -3.5 -5.5)
			(size 0.5 0.5)
			(property pad_prop_bga)
			(layers "F.Cu" "F.Mask" "F.Paste")
			(net 24 "+3V3")
			(pinfunction "VCCO_18")
			(pintype "passive")
			(solder_mask_margin 0.02)
		)
		(pad "K13" smd circle
			(at -2.5 -5.5)
			(size 0.5 0.5)
			(property pad_prop_bga)
			(layers "F.Cu" "F.Mask" "F.Paste")
			(net 464 "/FMC+ HSPC/FMC.IO4_P")
			(pinfunction "IO_L4P_T0_18")
			(pintype "bidirectional")
			(die_length 17.821)
			(solder_mask_margin 0.02)
		)
		(pad "K14" smd circle
			(at -1.5 -5.5)
			(size 0.5 0.5)
			(property pad_prop_bga)
			(layers "F.Cu" "F.Mask" "F.Paste")
			(net 441 "/FMC+ HSPC/FMC.IO5_P")
			(pinfunction "IO_L5P_T0_18")
			(pintype "bidirectional")
			(die_length 17.482)
			(solder_mask_margin 0.02)
		)
		(pad "K15" smd circle
			(at -0.5 -5.5)
			(size 0.5 0.5)
			(property pad_prop_bga)
			(layers "F.Cu" "F.Mask" "F.Paste")
			(net 450 "/FMC+ HSPC/FMC.IO2_N")
			(pinfunction "IO_L2N_T0_18")
			(pintype "bidirectional")
			(die_length 17.67)
			(solder_mask_margin 0.02)
		)
		(pad "K16" smd circle
			(at 0.5 -5.5)
			(size 0.5 0.5)
			(property pad_prop_bga)
			(layers "F.Cu" "F.Mask" "F.Paste")
			(net 414 "/FMC+ HSPC/FMC.IO1_N")
			(pinfunction "IO_L1N_T0_18")
			(pintype "bidirectional")
			(die_length 17.367)
			(solder_mask_margin 0.02)
		)
		(pad "K17" smd circle
			(at 1.5 -5.5)
			(size 0.5 0.5)
			(property pad_prop_bga)
			(layers "F.Cu" "F.Mask" "F.Paste")
			(net 1 "GND")
			(pinfunction "GND")
			(pintype "passive")
			(solder_mask_margin 0.02)
		)
		(pad "K18" smd circle
			(at 2.5 -5.5)
			(size 0.5 0.5)
			(property pad_prop_bga)
			(layers "F.Cu" "F.Mask" "F.Paste")
			(net 1039 "unconnected-(U1C-IO_L1P_T0_17-PadK18)")
			(pinfunction "IO_L1P_T0_17")
			(pintype "bidirectional+no_connect")
			(die_length 8.927)
			(solder_mask_margin 0.02)
		)
		(pad "K19" smd circle
			(at 3.5 -5.5)
			(size 0.5 0.5)
			(property pad_prop_bga)
			(layers "F.Cu" "F.Mask" "F.Paste")
			(net 1040 "unconnected-(U1C-IO_L6P_T0_17-PadK19)")
			(pinfunction "IO_L6P_T0_17")
			(pintype "bidirectional+no_connect")
			(die_length 7.177)
			(solder_mask_margin 0.02)
		)
		(pad "K20" smd circle
			(at 4.5 -5.5)
			(size 0.5 0.5)
			(property pad_prop_bga)
			(layers "F.Cu" "F.Mask" "F.Paste")
			(net 1041 "unconnected-(U1C-IO_L6N_T0_VREF_17-PadK20)")
			(pinfunction "IO_L6N_T0_VREF_17")
			(pintype "bidirectional+no_connect")
			(die_length 8.379)
			(solder_mask_margin 0.02)
		)
		(pad "K21" smd circle
			(at 5.5 -5.5)
			(size 0.5 0.5)
			(property pad_prop_bga)
			(layers "F.Cu" "F.Mask" "F.Paste")
			(net 1265 "/USER_IO.A40")
			(pinfunction "IO_L4N_T0_AD9N_15")
			(pintype "bidirectional")
			(die_length 13.872)
			(solder_mask_margin 0.02)
		)
		(pad "K22" smd circle
			(at 6.5 -5.5)
			(size 0.5 0.5)
			(property pad_prop_bga)
			(layers "F.Cu" "F.Mask" "F.Paste")
			(net 2 "VCC_USR_A")
			(pinfunction "VCCO_15")
			(pintype "passive")
			(solder_mask_margin 0.02)
		)
		(pad "K23" smd circle
			(at 7.5 -5.5)
			(size 0.5 0.5)
			(property pad_prop_bga)
			(layers "F.Cu" "F.Mask" "F.Paste")
			(net 1042 "unconnected-(U1B-IO_L3P_T0_DQS_AD1P_15-PadK23)")
			(pinfunction "IO_L3P_T0_DQS_AD1P_15")
			(pintype "bidirectional+no_connect")
			(die_length 12.884)
			(solder_mask_margin 0.02)
		)
		(pad "K24" smd circle
			(at 8.5 -5.5)
			(size 0.5 0.5)
			(property pad_prop_bga)
			(layers "F.Cu" "F.Mask" "F.Paste")
			(net 1043 "unconnected-(U1B-IO_L3N_T0_DQS_AD1N_15-PadK24)")
			(pinfunction "IO_L3N_T0_DQS_AD1N_15")
			(pintype "bidirectional+no_connect")
			(die_length 13.276)
			(solder_mask_margin 0.02)
		)
		(pad "K25" smd circle
			(at 9.5 -5.5)
			(size 0.5 0.5)
			(property pad_prop_bga)
			(layers "F.Cu" "F.Mask" "F.Paste")
			(net 1044 "unconnected-(U1B-IO_L12N_T1_MRCC_AD5N_15-PadK25)")
			(pinfunction "IO_L12N_T1_MRCC_AD5N_15")
			(pintype "bidirectional+no_connect")
			(die_length 15.47)
			(solder_mask_margin 0.02)
		)
		(pad "K26" smd circle
			(at 10.5 -5.5)
			(size 0.5 0.5)
			(property pad_prop_bga)
			(layers "F.Cu" "F.Mask" "F.Paste")
			(net 1264 "/USER_IO.A39")
			(pinfunction "IO_L10P_T1_AD4P_15")
			(pintype "bidirectional")
			(die_length 16.347)
			(solder_mask_margin 0.02)
		)
	)
)
